# S9S_MB_2U (Grand Teton) — schematic netlist excerpt (pin names and nets, part order shuffled) for the footprints in the layout excerpt that follows; sources: Cadence DE-HDL packaged netlist, KiCad conversion of 03242023_DA0F0TMBIJ0_F0T_Motherboard_J_brd_V01_OCP.brd

PR4248  Q_RES  0 5% EMPTY  pkg 0402LF  page 294 : A = PVCCFA_EHV_CPU1_NC2 ; B = PVCCFA_EHV_CPU1_VDD1
R548  Q_RES  49.9 1% CHIP  pkg 0402LF  page 14 : A = SVID_ALERT0_CPU0_R_N ; B = PVNN_TERM_CPU0

(kicad_pcb
	(version 20260206)
	(generator "pcbnew")
	(generator_version "10.0")
	(general
		(thickness 1.6)
		(legacy_teardrops no)
	)
	(paper "A4")
	(title_block
		(title "03242023_DA0F0TMBIJ0_F0T_Motherboard_J_brd_V01_OCP.brd")
		(comment 1 "Grand Teton / footprints 4593-4594 of 6105")
	)
	(layers
		(0 "F.Cu" signal "TOP")
		(4 "In1.Cu" signal "GND")
		(6 "In2.Cu" signal "IN1")
		(8 "In3.Cu" signal "GND1")
		(10 "In4.Cu" signal "IN2")
		(12 "In5.Cu" signal "GND2")
		(14 "In6.Cu" signal "IN3")
		(16 "In7.Cu" signal "GND3")
		(18 "In8.Cu" signal "VCC")
		(20 "In9.Cu" signal "VCC1")
		(22 "In10.Cu" signal "GND4")
		(24 "In11.Cu" signal "IN4")
		(26 "In12.Cu" signal "GND5")
		(28 "In13.Cu" signal "IN5")
		(30 "In14.Cu" signal "GND6")
		(32 "In15.Cu" signal "IN6")
		(34 "In16.Cu" signal "GND7")
		(2 "B.Cu" signal "BOTTOM")
		(9 "F.Adhes" user "F.Adhesive")
		(11 "B.Adhes" user "B.Adhesive")
		(13 "F.Paste" user "Package Geometry/Pastemask Top")
		(15 "B.Paste" user "Package Geometry/Pastemask Bottom")
		(5 "F.SilkS" user "Ref Des/Silkscreen Top")
		(7 "B.SilkS" user "Ref Des/Silkscreen Bottom")
		(1 "F.Mask" user "Board Geometry/Soldermask Top")
		(3 "B.Mask" user "Board Geometry/Soldermask Bottom")
		(17 "Dwgs.User" user "User.Drawings")
		(19 "Cmts.User" user "User.Comments")
		(21 "Eco1.User" user "User.Eco1")
		(23 "Eco2.User" user "User.Eco2")
		(25 "Edge.Cuts" user "Board Geometry/Outline")
		(27 "Margin" user)
		(31 "F.CrtYd" user "Package Geometry/Place Bound Top")
		(29 "B.CrtYd" user "Package Geometry/Place Bound Bottom")
		(35 "F.Fab" user "Ref Des/Assembly Top")
		(33 "B.Fab" user "Ref Des/Assembly Bottom")
	)
	(footprint ""
		(layer "B.Cu")
		(at 303.554638 -192.457578 90)
		(property "Reference" "R548"
			(at 0 0 90)
			(layer "B.SilkS")
			(hide yes)
			(effects
				(font
					(size 1.27 1.27)
				)
				(justify mirror)
			)
		)
		(property "Value" ""
			(at 0 0 90)
			(layer "B.Fab")
			(effects
				(font
					(size 1.27 1.27)
				)
				(justify mirror)
			)
		)
		(duplicate_pad_numbers_are_jumpers no)
		(fp_line
			(start 0.7874 -0.4064)
			(end -0.7874 -0.4064)
			(stroke
				(width 0.1524)
				(type default)
			)
			(layer "B.SilkS")
		)
		(fp_line
			(start -0.7874 -0.4064)
			(end -0.7874 0.4064)
			(stroke
				(width 0.1524)
				(type default)
			)
			(layer "B.SilkS")
		)
		(fp_line
			(start 0.7874 0.4064)
			(end 0.7874 -0.4064)
			(stroke
				(width 0.1524)
				(type default)
			)
			(layer "B.SilkS")
		)
		(fp_line
			(start -0.7874 0.4064)
			(end 0.7874 0.4064)
			(stroke
				(width 0.1524)
				(type default)
			)
			(layer "B.SilkS")
		)
		(fp_line
			(start 0.67945 -0.305054)
			(end 0.12065 -0.305054)
			(stroke
				(width 0.1)
				(type default)
			)
			(layer "B.Fab")
		)
		(fp_line
			(start 0.12065 -0.305054)
			(end 0.12065 -0.2794)
			(stroke
				(width 0.1)
				(type default)
			)
			(layer "B.Fab")
		)
		(fp_line
			(start -0.12065 -0.3048)
			(end -0.67945 -0.3048)
			(stroke
				(width 0.1)
				(type default)
			)
			(layer "B.Fab")
		)
		(fp_line
			(start -0.67945 -0.3048)
			(end -0.67945 0.3048)
			(stroke
				(width 0.1)
				(type default)
			)
			(layer "B.Fab")
		)
		(fp_line
			(start 0.12065 -0.2794)
			(end -0.12065 -0.2794)
			(stroke
				(width 0.1)
				(type default)
			)
			(layer "B.Fab")
		)
		(fp_line
			(start -0.12065 -0.2794)
			(end -0.12065 -0.3048)
			(stroke
				(width 0.1)
				(type default)
			)
			(layer "B.Fab")
		)
		(fp_line
			(start 0.12065 0.2794)
			(end 0.12065 0.3048)
			(stroke
				(width 0.1)
				(type default)
			)
			(layer "B.Fab")
		)
		(fp_line
			(start -0.120396 0.2794)
			(end 0.12065 0.2794)
			(stroke
				(width 0.1)
				(type default)
			)
			(layer "B.Fab")
		)
		(fp_line
			(start 0.67945 0.3048)
			(end 0.67945 -0.305054)
			(stroke
				(width 0.1)
				(type default)
			)
			(layer "B.Fab")
		)
		(fp_line
			(start 0.12065 0.3048)
			(end 0.67945 0.3048)
			(stroke
				(width 0.1)
				(type default)
			)
			(layer "B.Fab")
		)
		(fp_line
			(start -0.120396 0.3048)
			(end -0.120396 0.2794)
			(stroke
				(width 0.1)
				(type default)
			)
			(layer "B.Fab")
		)
		(fp_line
			(start -0.67945 0.3048)
			(end -0.120396 0.3048)
			(stroke
				(width 0.1)
				(type default)
			)
			(layer "B.Fab")
		)
		(pad "1" smd circle
			(at 0.40005 0 270)
			(size 0 0)
			(layers "B.Cu" "B.Mask" "B.Paste")
			(net "SVID_ALERT0_CPU0_R_N")
		)
		(pad "2" smd circle
			(at -0.40005 0 270)
			(size 0 0)
			(layers "B.Cu" "B.Mask" "B.Paste")
			(net "PVNN_TERM_CPU0")
		)
	)
	(footprint ""
		(layer "B.Cu")
		(at 49.15408 -172.989748)
		(property "Reference" "PR4248"
			(at 0 0 0)
			(layer "B.SilkS")
			(hide yes)
			(effects
				(font
					(size 1.27 1.27)
				)
				(justify mirror)
			)
		)
		(property "Value" ""
			(at 0 0 0)
			(layer "B.Fab")
			(effects
				(font
					(size 1.27 1.27)
				)
				(justify mirror)
			)
		)
		(duplicate_pad_numbers_are_jumpers no)
		(fp_line
			(start -0.7874 -0.4064)
			(end -0.7874 0.4064)
			(stroke
				(width 0.1524)
				(type default)
			)
			(layer "B.SilkS")
		)
		(fp_line
			(start -0.7874 0.4064)
			(end 0.7874 0.4064)
			(stroke
				(width 0.1524)
				(type default)
			)
			(layer "B.SilkS")
		)
		(fp_line
			(start 0.7874 -0.4064)
			(end -0.7874 -0.4064)
			(stroke
				(width 0.1524)
				(type default)
			)
			(layer "B.SilkS")
		)
		(fp_line
			(start 0.7874 0.4064)
			(end 0.7874 -0.4064)
			(stroke
				(width 0.1524)
				(type default)
			)
			(layer "B.SilkS")
		)
		(fp_line
			(start -0.67945 -0.3048)
			(end -0.67945 0.3048)
			(stroke
				(width 0.1)
				(type default)
			)
			(layer "B.Fab")
		)
		(fp_line
			(start -0.67945 0.3048)
			(end -0.120396 0.3048)
			(stroke
				(width 0.1)
				(type default)
			)
			(layer "B.Fab")
		)
		(fp_line
			(start -0.12065 -0.3048)
			(end -0.67945 -0.3048)
			(stroke
				(width 0.1)
				(type default)
			)
			(layer "B.Fab")
		)
		(fp_line
			(start -0.12065 -0.2794)
			(end -0.12065 -0.3048)
			(stroke
				(width 0.1)
				(type default)
			)
			(layer "B.Fab")
		)
		(fp_line
			(start -0.120396 0.2794)
			(end 0.12065 0.2794)
			(stroke
				(width 0.1)
				(type default)
			)
			(layer "B.Fab")
		)
		(fp_line
			(start -0.120396 0.3048)
			(end -0.120396 0.2794)
			(stroke
				(width 0.1)
				(type default)
			)
			(layer "B.Fab")
		)
		(fp_line
			(start 0.12065 -0.305054)
			(end 0.12065 -0.2794)
			(stroke
				(width 0.1)
				(type default)
			)
			(layer "B.Fab")
		)
		(fp_line
			(start 0.12065 -0.2794)
			(end -0.12065 -0.2794)
			(stroke
				(width 0.1)
				(type default)
			)
			(layer "B.Fab")
		)
		(fp_line
			(start 0.12065 0.2794)
			(end 0.12065 0.3048)
			(stroke
				(width 0.1)
				(type default)
			)
			(layer "B.Fab")
		)
		(fp_line
			(start 0.12065 0.3048)
			(end 0.67945 0.3048)
			(stroke
				(width 0.1)
				(type default)
			)
			(layer "B.Fab")
		)
		(fp_line
			(start 0.67945 -0.305054)
			(end 0.12065 -0.305054)
			(stroke
				(width 0.1)
				(type default)
			)
			(layer "B.Fab")
		)
		(fp_line
			(start 0.67945 0.3048)
			(end 0.67945 -0.305054)
			(stroke
				(width 0.1)
				(type default)
			)
			(layer "B.Fab")
		)
		(pad "1" smd circle
			(at 0.40005 0 180)
			(size 0 0)
			(layers "B.Cu" "B.Mask" "B.Paste")
			(net "PVCCFA_EHV_CPU1_NC2")
		)
		(pad "2" smd circle
			(at -0.40005 0 180)
			(size 0 0)
			(layers "B.Cu" "B.Mask" "B.Paste")
			(net "PVCCFA_EHV_CPU1_VDD1")
		)
	)
)
